# T6G (Grand Teton) — schematic netlist excerpt (pin names and nets, part order shuffled) for the footprints in the layout excerpt that follows; sources: Cadence DE-HDL packaged netlist, KiCad conversion of 04192023_DAF0TMB3IC0_F0TG_MB_C_brd_V02_OCP.brd

R2921  Q_RES  10K 1% EMPTY  pkg 0402LF  page 245 : A = P3V3_AUX ; B = RST_SMB_SWITCH_N
R466  Q_RES  33 5% CHIP  pkg 0402LF  page 29 : A = SPI_CPU0_D2 ; B = SPI_CPU0_R_D2

(kicad_pcb
	(version 20260206)
	(generator "pcbnew")
	(generator_version "10.0")
	(general
		(thickness 1.6)
		(legacy_teardrops no)
	)
	(paper "A4")
	(title_block
		(title "04192023_DAF0TMB3IC0_F0TG_MB_C_brd_V02_OCP.brd")
		(comment 1 "Grand Teton / footprints 2224-2225 of 8354")
	)
	(layers
		(0 "F.Cu" signal "TOP")
		(4 "In1.Cu" signal "GND")
		(6 "In2.Cu" signal "IN1")
		(8 "In3.Cu" signal "GND1")
		(10 "In4.Cu" signal "IN2")
		(12 "In5.Cu" signal "GND2")
		(14 "In6.Cu" signal "IN3")
		(16 "In7.Cu" signal "GND3")
		(18 "In8.Cu" signal "VCC")
		(20 "In9.Cu" signal "VCC1")
		(22 "In10.Cu" signal "GND4")
		(24 "In11.Cu" signal "IN4")
		(26 "In12.Cu" signal "GND5")
		(28 "In13.Cu" signal "IN5")
		(30 "In14.Cu" signal "GND6")
		(32 "In15.Cu" signal "IN6")
		(34 "In16.Cu" signal "GND7")
		(2 "B.Cu" signal "BOTTOM")
		(9 "F.Adhes" user "F.Adhesive")
		(11 "B.Adhes" user "B.Adhesive")
		(13 "F.Paste" user "Package Geometry/Pastemask Top")
		(15 "B.Paste" user "Package Geometry/Pastemask Bottom")
		(5 "F.SilkS" user "Ref Des/Silkscreen Top")
		(7 "B.SilkS" user "Ref Des/Silkscreen Bottom")
		(1 "F.Mask" user "Board Geometry/Soldermask Top")
		(3 "B.Mask" user "Board Geometry/Soldermask Bottom")
		(17 "Dwgs.User" user "User.Drawings")
		(19 "Cmts.User" user "User.Comments")
		(21 "Eco1.User" user "User.Eco1")
		(23 "Eco2.User" user "User.Eco2")
		(25 "Edge.Cuts" user "Board Geometry/Outline")
		(27 "Margin" user)
		(31 "F.CrtYd" user "Package Geometry/Place Bound Top")
		(29 "B.CrtYd" user "Package Geometry/Place Bound Bottom")
		(35 "F.Fab" user "Ref Des/Assembly Top")
		(33 "B.Fab" user "Ref Des/Assembly Bottom")
	)
	(footprint ""
		(layer "F.Cu")
		(at 400.407378 -327.395332 180)
		(property "Reference" "R466"
			(at 0 0 180)
			(layer "F.SilkS")
			(hide yes)
			(effects
				(font
					(size 1.27 1.27)
				)
			)
		)
		(property "Value" ""
			(at 0 0 180)
			(layer "F.Fab")
			(effects
				(font
					(size 1.27 1.27)
				)
			)
		)
		(duplicate_pad_numbers_are_jumpers no)
		(fp_line
			(start 0.7874 0.4064)
			(end -0.7874 0.4064)
			(stroke
				(width 0.1524)
				(type default)
			)
			(layer "F.SilkS")
		)
		(fp_line
			(start 0.7874 -0.4064)
			(end 0.7874 0.4064)
			(stroke
				(width 0.1524)
				(type default)
			)
			(layer "F.SilkS")
		)
		(fp_line
			(start -0.7874 0.4064)
			(end -0.7874 -0.4064)
			(stroke
				(width 0.1524)
				(type default)
			)
			(layer "F.SilkS")
		)
		(fp_line
			(start -0.7874 -0.4064)
			(end 0.7874 -0.4064)
			(stroke
				(width 0.1524)
				(type default)
			)
			(layer "F.SilkS")
		)
		(fp_line
			(start 0.67945 0.3048)
			(end 0.120396 0.3048)
			(stroke
				(width 0.1)
				(type default)
			)
			(layer "F.Fab")
		)
		(fp_line
			(start 0.67945 -0.3048)
			(end 0.67945 0.3048)
			(stroke
				(width 0.1)
				(type default)
			)
			(layer "F.Fab")
		)
		(fp_line
			(start 0.12065 -0.2794)
			(end 0.12065 -0.3048)
			(stroke
				(width 0.1)
				(type default)
			)
			(layer "F.Fab")
		)
		(fp_line
			(start 0.12065 -0.3048)
			(end 0.67945 -0.3048)
			(stroke
				(width 0.1)
				(type default)
			)
			(layer "F.Fab")
		)
		(fp_line
			(start 0.120396 0.3048)
			(end 0.120396 0.2794)
			(stroke
				(width 0.1)
				(type default)
			)
			(layer "F.Fab")
		)
		(fp_line
			(start 0.120396 0.2794)
			(end -0.12065 0.2794)
			(stroke
				(width 0.1)
				(type default)
			)
			(layer "F.Fab")
		)
		(fp_line
			(start -0.12065 0.3048)
			(end -0.67945 0.3048)
			(stroke
				(width 0.1)
				(type default)
			)
			(layer "F.Fab")
		)
		(fp_line
			(start -0.12065 0.2794)
			(end -0.12065 0.3048)
			(stroke
				(width 0.1)
				(type default)
			)
			(layer "F.Fab")
		)
		(fp_line
			(start -0.12065 -0.2794)
			(end 0.12065 -0.2794)
			(stroke
				(width 0.1)
				(type default)
			)
			(layer "F.Fab")
		)
		(fp_line
			(start -0.12065 -0.305054)
			(end -0.12065 -0.2794)
			(stroke
				(width 0.1)
				(type default)
			)
			(layer "F.Fab")
		)
		(fp_line
			(start -0.67945 0.3048)
			(end -0.67945 -0.305054)
			(stroke
				(width 0.1)
				(type default)
			)
			(layer "F.Fab")
		)
		(fp_line
			(start -0.67945 -0.305054)
			(end -0.12065 -0.305054)
			(stroke
				(width 0.1)
				(type default)
			)
			(layer "F.Fab")
		)
		(pad "1" smd circle
			(at -0.40005 0 180)
			(size 0 0)
			(layers "F.Cu" "F.Mask" "F.Paste")
			(net "SPI_CPU0_D2")
		)
		(pad "2" smd circle
			(at 0.40005 0 180)
			(size 0 0)
			(layers "F.Cu" "F.Mask" "F.Paste")
			(net "SPI_CPU0_R_D2")
		)
	)
	(footprint ""
		(layer "F.Cu")
		(at 182.664608 -413.786574 -90)
		(property "Reference" "R2921"
			(at 0 0 270)
			(layer "F.SilkS")
			(hide yes)
			(effects
				(font
					(size 1.27 1.27)
				)
			)
		)
		(property "Value" ""
			(at 0 0 270)
			(layer "F.Fab")
			(effects
				(font
					(size 1.27 1.27)
				)
			)
		)
		(duplicate_pad_numbers_are_jumpers no)
		(fp_line
			(start -0.7874 0.4064)
			(end -0.7874 -0.4064)
			(stroke
				(width 0.1524)
				(type default)
			)
			(layer "F.SilkS")
		)
		(fp_line
			(start 0.7874 0.4064)
			(end -0.7874 0.4064)
			(stroke
				(width 0.1524)
				(type default)
			)
			(layer "F.SilkS")
		)
		(fp_line
			(start -0.7874 -0.4064)
			(end 0.7874 -0.4064)
			(stroke
				(width 0.1524)
				(type default)
			)
			(layer "F.SilkS")
		)
		(fp_line
			(start 0.7874 -0.4064)
			(end 0.7874 0.4064)
			(stroke
				(width 0.1524)
				(type default)
			)
			(layer "F.SilkS")
		)
		(fp_line
			(start -0.67945 0.3048)
			(end -0.67945 -0.305054)
			(stroke
				(width 0.1)
				(type default)
			)
			(layer "F.Fab")
		)
		(fp_line
			(start -0.12065 0.3048)
			(end -0.67945 0.3048)
			(stroke
				(width 0.1)
				(type default)
			)
			(layer "F.Fab")
		)
		(fp_line
			(start 0.120396 0.3048)
			(end 0.120396 0.2794)
			(stroke
				(width 0.1)
				(type default)
			)
			(layer "F.Fab")
		)
		(fp_line
			(start 0.67945 0.3048)
			(end 0.120396 0.3048)
			(stroke
				(width 0.1)
				(type default)
			)
			(layer "F.Fab")
		)
		(fp_line
			(start -0.12065 0.2794)
			(end -0.12065 0.3048)
			(stroke
				(width 0.1)
				(type default)
			)
			(layer "F.Fab")
		)
		(fp_line
			(start 0.120396 0.2794)
			(end -0.12065 0.2794)
			(stroke
				(width 0.1)
				(type default)
			)
			(layer "F.Fab")
		)
		(fp_line
			(start -0.12065 -0.2794)
			(end 0.12065 -0.2794)
			(stroke
				(width 0.1)
				(type default)
			)
			(layer "F.Fab")
		)
		(fp_line
			(start 0.12065 -0.2794)
			(end 0.12065 -0.3048)
			(stroke
				(width 0.1)
				(type default)
			)
			(layer "F.Fab")
		)
		(fp_line
			(start 0.12065 -0.3048)
			(end 0.67945 -0.3048)
			(stroke
				(width 0.1)
				(type default)
			)
			(layer "F.Fab")
		)
		(fp_line
			(start 0.67945 -0.3048)
			(end 0.67945 0.3048)
			(stroke
				(width 0.1)
				(type default)
			)
			(layer "F.Fab")
		)
		(fp_line
			(start -0.67945 -0.305054)
			(end -0.12065 -0.305054)
			(stroke
				(width 0.1)
				(type default)
			)
			(layer "F.Fab")
		)
		(fp_line
			(start -0.12065 -0.305054)
			(end -0.12065 -0.2794)
			(stroke
				(width 0.1)
				(type default)
			)
			(layer "F.Fab")
		)
		(pad "1" smd circle
			(at -0.40005 0 270)
			(size 0 0)
			(layers "F.Cu" "F.Mask" "F.Paste")
			(net "P3V3_AUX")
		)
		(pad "2" smd circle
			(at 0.40005 0 270)
			(size 0 0)
			(layers "F.Cu" "F.Mask" "F.Paste")
			(net "RST_SMB_SWITCH_N")
		)
	)
)
